(kicad_pcb
	(version 20260206)
	(generator "pcbnew")
	(generator_version "10.0")
	(general
		(thickness 1.6)
		(legacy_teardrops no)
	)
	(paper "A4")
	(title_block
		(title "01162023_DA0F0TEBIF0_F0T_Expander_BD_F_brd_V02_OCP.brd")
		(comment 1 "Grand Teton / footprints 2246-2251 of 9728")
	)
	(layers
		(0 "F.Cu" signal "TOP")
		(4 "In1.Cu" signal "GND")
		(6 "In2.Cu" signal "VCC")
		(8 "In3.Cu" signal "VCC1")
		(10 "In4.Cu" signal "GND1")
		(12 "In5.Cu" signal "IN1")
		(14 "In6.Cu" signal "GND2")
		(16 "In7.Cu" signal "IN2")
		(18 "In8.Cu" signal "GND3")
		(20 "In9.Cu" signal "IN3")
		(22 "In10.Cu" signal "GND4")
		(24 "In11.Cu" signal "IN4")
		(26 "In12.Cu" signal "GND5")
		(28 "In13.Cu" signal "IN5")
		(30 "In14.Cu" signal "GND6")
		(32 "In15.Cu" signal "IN6")
		(34 "In16.Cu" signal "GND7")
		(2 "B.Cu" signal "BOTTOM")
		(9 "F.Adhes" user "F.Adhesive")
		(11 "B.Adhes" user "B.Adhesive")
		(13 "F.Paste" user "Package Geometry/Pastemask Top")
		(15 "B.Paste" user "Package Geometry/Pastemask Bottom")
		(5 "F.SilkS" user "Ref Des/Silkscreen Top")
		(7 "B.SilkS" user "Ref Des/Silkscreen Bottom")
		(1 "F.Mask" user "Board Geometry/Soldermask Top")
		(3 "B.Mask" user "Board Geometry/Soldermask Bottom")
		(17 "Dwgs.User" user "User.Drawings")
		(19 "Cmts.User" user "User.Comments")
		(21 "Eco1.User" user "User.Eco1")
		(23 "Eco2.User" user "User.Eco2")
		(25 "Edge.Cuts" user "Board Geometry/Outline")
		(27 "Margin" user)
		(31 "F.CrtYd" user "Package Geometry/Place Bound Top")
		(29 "B.CrtYd" user "Package Geometry/Place Bound Bottom")
		(35 "F.Fab" user "Ref Des/Assembly Top")
		(33 "B.Fab" user "Ref Des/Assembly Bottom")
	)
	(footprint ""
		(layer "F.Cu")
		(at 253.147322 -19.33956)
		(property "Reference" "C3930"
			(at 0 0 0)
			(layer "F.SilkS")
			(hide yes)
			(effects
				(font
					(size 1.27 1.27)
				)
			)
		)
		(property "Value" ""
			(at 0 0 0)
			(layer "F.Fab")
			(effects
				(font
					(size 1.27 1.27)
				)
			)
		)
		(duplicate_pad_numbers_are_jumpers no)
		(fp_line
			(start -0.7874 -0.4064)
			(end 0.7874 -0.4064)
			(stroke
				(width 0.1524)
				(type default)
			)
			(layer "F.SilkS")
		)
		(fp_line
			(start -0.7874 0.4064)
			(end -0.7874 -0.4064)
			(stroke
				(width 0.1524)
				(type default)
			)
			(layer "F.SilkS")
		)
		(fp_line
			(start 0.7874 -0.4064)
			(end 0.7874 0.4064)
			(stroke
				(width 0.1524)
				(type default)
			)
			(layer "F.SilkS")
		)
		(fp_line
			(start 0.7874 0.4064)
			(end -0.7874 0.4064)
			(stroke
				(width 0.1524)
				(type default)
			)
			(layer "F.SilkS")
		)
		(fp_line
			(start -0.67945 -0.305054)
			(end -0.12065 -0.305054)
			(stroke
				(width 0.1)
				(type default)
			)
			(layer "F.Fab")
		)
		(fp_line
			(start -0.67945 0.3048)
			(end -0.67945 -0.305054)
			(stroke
				(width 0.1)
				(type default)
			)
			(layer "F.Fab")
		)
		(fp_line
			(start -0.12065 -0.305054)
			(end -0.12065 -0.2794)
			(stroke
				(width 0.1)
				(type default)
			)
			(layer "F.Fab")
		)
		(fp_line
			(start -0.12065 -0.2794)
			(end 0.12065 -0.2794)
			(stroke
				(width 0.1)
				(type default)
			)
			(layer "F.Fab")
		)
		(fp_line
			(start -0.12065 0.2794)
			(end -0.12065 0.3048)
			(stroke
				(width 0.1)
				(type default)
			)
			(layer "F.Fab")
		)
		(fp_line
			(start -0.12065 0.3048)
			(end -0.67945 0.3048)
			(stroke
				(width 0.1)
				(type default)
			)
			(layer "F.Fab")
		)
		(fp_line
			(start 0.120396 0.2794)
			(end -0.12065 0.2794)
			(stroke
				(width 0.1)
				(type default)
			)
			(layer "F.Fab")
		)
		(fp_line
			(start 0.120396 0.3048)
			(end 0.120396 0.2794)
			(stroke
				(width 0.1)
				(type default)
			)
			(layer "F.Fab")
		)
		(fp_line
			(start 0.12065 -0.3048)
			(end 0.67945 -0.3048)
			(stroke
				(width 0.1)
				(type default)
			)
			(layer "F.Fab")
		)
		(fp_line
			(start 0.12065 -0.2794)
			(end 0.12065 -0.3048)
			(stroke
				(width 0.1)
				(type default)
			)
			(layer "F.Fab")
		)
		(fp_line
			(start 0.67945 -0.3048)
			(end 0.67945 0.3048)
			(stroke
				(width 0.1)
				(type default)
			)
			(layer "F.Fab")
		)
		(fp_line
			(start 0.67945 0.3048)
			(end 0.120396 0.3048)
			(stroke
				(width 0.1)
				(type default)
			)
			(layer "F.Fab")
		)
		(pad "1" smd circle
			(at -0.40005 0)
			(size 0 0)
			(layers "F.Cu" "F.Mask" "F.Paste")
			(net "P12V_SSD8")
		)
		(pad "2" smd circle
			(at 0.40005 0)
			(size 0 0)
			(layers "F.Cu" "F.Mask" "F.Paste")
			(net "GND")
		)
	)
	(footprint ""
		(layer "F.Cu")
		(at 198.567294 -366.63503)
		(property "Reference" "PR1"
			(at 0 0 0)
			(layer "F.SilkS")
			(hide yes)
			(effects
				(font
					(size 1.27 1.27)
				)
			)
		)
		(property "Value" ""
			(at 0 0 0)
			(layer "F.Fab")
			(effects
				(font
					(size 1.27 1.27)
				)
			)
		)
		(duplicate_pad_numbers_are_jumpers no)
		(fp_line
			(start -0.7874 -0.4064)
			(end 0.7874 -0.4064)
			(stroke
				(width 0.1524)
				(type default)
			)
			(layer "F.SilkS")
		)
		(fp_line
			(start -0.7874 0.4064)
			(end -0.7874 -0.4064)
			(stroke
				(width 0.1524)
				(type default)
			)
			(layer "F.SilkS")
		)
		(fp_line
			(start 0.7874 -0.4064)
			(end 0.7874 0.4064)
			(stroke
				(width 0.1524)
				(type default)
			)
			(layer "F.SilkS")
		)
		(fp_line
			(start 0.7874 0.4064)
			(end -0.7874 0.4064)
			(stroke
				(width 0.1524)
				(type default)
			)
			(layer "F.SilkS")
		)
		(fp_line
			(start -0.67945 -0.305054)
			(end -0.12065 -0.305054)
			(stroke
				(width 0.1)
				(type default)
			)
			(layer "F.Fab")
		)
		(fp_line
			(start -0.67945 0.3048)
			(end -0.67945 -0.305054)
			(stroke
				(width 0.1)
				(type default)
			)
			(layer "F.Fab")
		)
		(fp_line
			(start -0.12065 -0.305054)
			(end -0.12065 -0.2794)
			(stroke
				(width 0.1)
				(type default)
			)
			(layer "F.Fab")
		)
		(fp_line
			(start -0.12065 -0.2794)
			(end 0.12065 -0.2794)
			(stroke
				(width 0.1)
				(type default)
			)
			(layer "F.Fab")
		)
		(fp_line
			(start -0.12065 0.2794)
			(end -0.12065 0.3048)
			(stroke
				(width 0.1)
				(type default)
			)
			(layer "F.Fab")
		)
		(fp_line
			(start -0.12065 0.3048)
			(end -0.67945 0.3048)
			(stroke
				(width 0.1)
				(type default)
			)
			(layer "F.Fab")
		)
		(fp_line
			(start 0.120396 0.2794)
			(end -0.12065 0.2794)
			(stroke
				(width 0.1)
				(type default)
			)
			(layer "F.Fab")
		)
		(fp_line
			(start 0.120396 0.3048)
			(end 0.120396 0.2794)
			(stroke
				(width 0.1)
				(type default)
			)
			(layer "F.Fab")
		)
		(fp_line
			(start 0.12065 -0.3048)
			(end 0.67945 -0.3048)
			(stroke
				(width 0.1)
				(type default)
			)
			(layer "F.Fab")
		)
		(fp_line
			(start 0.12065 -0.2794)
			(end 0.12065 -0.3048)
			(stroke
				(width 0.1)
				(type default)
			)
			(layer "F.Fab")
		)
		(fp_line
			(start 0.67945 -0.3048)
			(end 0.67945 0.3048)
			(stroke
				(width 0.1)
				(type default)
			)
			(layer "F.Fab")
		)
		(fp_line
			(start 0.67945 0.3048)
			(end 0.120396 0.3048)
			(stroke
				(width 0.1)
				(type default)
			)
			(layer "F.Fab")
		)
		(pad "1" smd circle
			(at -0.40005 0)
			(size 0 0)
			(layers "F.Cu" "F.Mask" "F.Paste")
			(net "GND")
		)
		(pad "2" smd circle
			(at 0.40005 0)
			(size 0 0)
			(layers "F.Cu" "F.Mask" "F.Paste")
			(net "AGND_HSC")
		)
	)
	(footprint ""
		(layer "F.Cu")
		(at 98.657156 -102.088442)
		(property "Reference" "PC320"
			(at 0 0 0)
			(layer "F.SilkS")
			(hide yes)
			(effects
				(font
					(size 1.27 1.27)
				)
			)
		)
		(property "Value" ""
			(at 0 0 0)
			(layer "F.Fab")
			(effects
				(font
					(size 1.27 1.27)
				)
			)
		)
		(duplicate_pad_numbers_are_jumpers no)
		(fp_line
			(start -0.7874 -0.4064)
			(end 0.7874 -0.4064)
			(stroke
				(width 0.1524)
				(type default)
			)
			(layer "F.SilkS")
		)
		(fp_line
			(start -0.7874 0.4064)
			(end -0.7874 -0.4064)
			(stroke
				(width 0.1524)
				(type default)
			)
			(layer "F.SilkS")
		)
		(fp_line
			(start 0.7874 -0.4064)
			(end 0.7874 0.4064)
			(stroke
				(width 0.1524)
				(type default)
			)
			(layer "F.SilkS")
		)
		(fp_line
			(start 0.7874 0.4064)
			(end -0.7874 0.4064)
			(stroke
				(width 0.1524)
				(type default)
			)
			(layer "F.SilkS")
		)
		(fp_line
			(start -0.67945 -0.305054)
			(end -0.12065 -0.305054)
			(stroke
				(width 0.1)
				(type default)
			)
			(layer "F.Fab")
		)
		(fp_line
			(start -0.67945 0.3048)
			(end -0.67945 -0.305054)
			(stroke
				(width 0.1)
				(type default)
			)
			(layer "F.Fab")
		)
		(fp_line
			(start -0.12065 -0.305054)
			(end -0.12065 -0.2794)
			(stroke
				(width 0.1)
				(type default)
			)
			(layer "F.Fab")
		)
		(fp_line
			(start -0.12065 -0.2794)
			(end 0.12065 -0.2794)
			(stroke
				(width 0.1)
				(type default)
			)
			(layer "F.Fab")
		)
		(fp_line
			(start -0.12065 0.2794)
			(end -0.12065 0.3048)
			(stroke
				(width 0.1)
				(type default)
			)
			(layer "F.Fab")
		)
		(fp_line
			(start -0.12065 0.3048)
			(end -0.67945 0.3048)
			(stroke
				(width 0.1)
				(type default)
			)
			(layer "F.Fab")
		)
		(fp_line
			(start 0.120396 0.2794)
			(end -0.12065 0.2794)
			(stroke
				(width 0.1)
				(type default)
			)
			(layer "F.Fab")
		)
		(fp_line
			(start 0.120396 0.3048)
			(end 0.120396 0.2794)
			(stroke
				(width 0.1)
				(type default)
			)
			(layer "F.Fab")
		)
		(fp_line
			(start 0.12065 -0.3048)
			(end 0.67945 -0.3048)
			(stroke
				(width 0.1)
				(type default)
			)
			(layer "F.Fab")
		)
		(fp_line
			(start 0.12065 -0.2794)
			(end 0.12065 -0.3048)
			(stroke
				(width 0.1)
				(type default)
			)
			(layer "F.Fab")
		)
		(fp_line
			(start 0.67945 -0.3048)
			(end 0.67945 0.3048)
			(stroke
				(width 0.1)
				(type default)
			)
			(layer "F.Fab")
		)
		(fp_line
			(start 0.67945 0.3048)
			(end 0.120396 0.3048)
			(stroke
				(width 0.1)
				(type default)
			)
			(layer "F.Fab")
		)
		(pad "1" smd circle
			(at -0.40005 0)
			(size 0 0)
			(layers "F.Cu" "F.Mask" "F.Paste")
			(net "P12V_NIC1_R")
		)
		(pad "2" smd circle
			(at 0.40005 0)
			(size 0 0)
			(layers "F.Cu" "F.Mask" "F.Paste")
			(net "GND")
		)
	)
	(footprint ""
		(layer "F.Cu")
		(at 408.510994 -61.386974)
		(property "Reference" "R4506"
			(at 0 0 0)
			(layer "F.SilkS")
			(hide yes)
			(effects
				(font
					(size 1.27 1.27)
				)
			)
		)
		(property "Value" ""
			(at 0 0 0)
			(layer "F.Fab")
			(effects
				(font
					(size 1.27 1.27)
				)
			)
		)
		(duplicate_pad_numbers_are_jumpers no)
		(fp_line
			(start -0.7874 -0.4064)
			(end 0.7874 -0.4064)
			(stroke
				(width 0.1524)
				(type default)
			)
			(layer "F.SilkS")
		)
		(fp_line
			(start -0.7874 0.4064)
			(end -0.7874 -0.4064)
			(stroke
				(width 0.1524)
				(type default)
			)
			(layer "F.SilkS")
		)
		(fp_line
			(start 0.7874 -0.4064)
			(end 0.7874 0.4064)
			(stroke
				(width 0.1524)
				(type default)
			)
			(layer "F.SilkS")
		)
		(fp_line
			(start 0.7874 0.4064)
			(end -0.7874 0.4064)
			(stroke
				(width 0.1524)
				(type default)
			)
			(layer "F.SilkS")
		)
		(fp_line
			(start -0.67945 -0.305054)
			(end -0.12065 -0.305054)
			(stroke
				(width 0.1)
				(type default)
			)
			(layer "F.Fab")
		)
		(fp_line
			(start -0.67945 0.3048)
			(end -0.67945 -0.305054)
			(stroke
				(width 0.1)
				(type default)
			)
			(layer "F.Fab")
		)
		(fp_line
			(start -0.12065 -0.305054)
			(end -0.12065 -0.2794)
			(stroke
				(width 0.1)
				(type default)
			)
			(layer "F.Fab")
		)
		(fp_line
			(start -0.12065 -0.2794)
			(end 0.12065 -0.2794)
			(stroke
				(width 0.1)
				(type default)
			)
			(layer "F.Fab")
		)
		(fp_line
			(start -0.12065 0.2794)
			(end -0.12065 0.3048)
			(stroke
				(width 0.1)
				(type default)
			)
			(layer "F.Fab")
		)
		(fp_line
			(start -0.12065 0.3048)
			(end -0.67945 0.3048)
			(stroke
				(width 0.1)
				(type default)
			)
			(layer "F.Fab")
		)
		(fp_line
			(start 0.120396 0.2794)
			(end -0.12065 0.2794)
			(stroke
				(width 0.1)
				(type default)
			)
			(layer "F.Fab")
		)
		(fp_line
			(start 0.120396 0.3048)
			(end 0.120396 0.2794)
			(stroke
				(width 0.1)
				(type default)
			)
			(layer "F.Fab")
		)
		(fp_line
			(start 0.12065 -0.3048)
			(end 0.67945 -0.3048)
			(stroke
				(width 0.1)
				(type default)
			)
			(layer "F.Fab")
		)
		(fp_line
			(start 0.12065 -0.2794)
			(end 0.12065 -0.3048)
			(stroke
				(width 0.1)
				(type default)
			)
			(layer "F.Fab")
		)
		(fp_line
			(start 0.67945 -0.3048)
			(end 0.67945 0.3048)
			(stroke
				(width 0.1)
				(type default)
			)
			(layer "F.Fab")
		)
		(fp_line
			(start 0.67945 0.3048)
			(end 0.120396 0.3048)
			(stroke
				(width 0.1)
				(type default)
			)
			(layer "F.Fab")
		)
		(pad "1" smd circle
			(at -0.40005 0)
			(size 0 0)
			(layers "F.Cu" "F.Mask" "F.Paste")
			(net "PWRGD_P3V3_SSD14")
		)
		(pad "2" smd circle
			(at 0.40005 0)
			(size 0 0)
			(layers "F.Cu" "F.Mask" "F.Paste")
			(net "PWRGD_P3V3_SSD14_R")
		)
	)
	(footprint ""
		(layer "F.Cu")
		(at 187.754768 -22.867366 90)
		(property "Reference" "C3920"
			(at 0 0 90)
			(layer "F.SilkS")
			(hide yes)
			(effects
				(font
					(size 1.27 1.27)
				)
			)
		)
		(property "Value" ""
			(at 0 0 90)
			(layer "F.Fab")
			(effects
				(font
					(size 1.27 1.27)
				)
			)
		)
		(duplicate_pad_numbers_are_jumpers no)
		(fp_line
			(start 0.7874 -0.4064)
			(end 0.7874 0.4064)
			(stroke
				(width 0.1524)
				(type default)
			)
			(layer "F.SilkS")
		)
		(fp_line
			(start -0.7874 -0.4064)
			(end 0.7874 -0.4064)
			(stroke
				(width 0.1524)
				(type default)
			)
			(layer "F.SilkS")
		)
		(fp_line
			(start 0.7874 0.4064)
			(end -0.7874 0.4064)
			(stroke
				(width 0.1524)
				(type default)
			)
			(layer "F.SilkS")
		)
		(fp_line
			(start -0.7874 0.4064)
			(end -0.7874 -0.4064)
			(stroke
				(width 0.1524)
				(type default)
			)
			(layer "F.SilkS")
		)
		(fp_line
			(start -0.12065 -0.305054)
			(end -0.12065 -0.2794)
			(stroke
				(width 0.1)
				(type default)
			)
			(layer "F.Fab")
		)
		(fp_line
			(start -0.67945 -0.305054)
			(end -0.12065 -0.305054)
			(stroke
				(width 0.1)
				(type default)
			)
			(layer "F.Fab")
		)
		(fp_line
			(start 0.67945 -0.3048)
			(end 0.67945 0.3048)
			(stroke
				(width 0.1)
				(type default)
			)
			(layer "F.Fab")
		)
		(fp_line
			(start 0.12065 -0.3048)
			(end 0.67945 -0.3048)
			(stroke
				(width 0.1)
				(type default)
			)
			(layer "F.Fab")
		)
		(fp_line
			(start 0.12065 -0.2794)
			(end 0.12065 -0.3048)
			(stroke
				(width 0.1)
				(type default)
			)
			(layer "F.Fab")
		)
		(fp_line
			(start -0.12065 -0.2794)
			(end 0.12065 -0.2794)
			(stroke
				(width 0.1)
				(type default)
			)
			(layer "F.Fab")
		)
		(fp_line
			(start 0.120396 0.2794)
			(end -0.12065 0.2794)
			(stroke
				(width 0.1)
				(type default)
			)
			(layer "F.Fab")
		)
		(fp_line
			(start -0.12065 0.2794)
			(end -0.12065 0.3048)
			(stroke
				(width 0.1)
				(type default)
			)
			(layer "F.Fab")
		)
		(fp_line
			(start 0.67945 0.3048)
			(end 0.120396 0.3048)
			(stroke
				(width 0.1)
				(type default)
			)
			(layer "F.Fab")
		)
		(fp_line
			(start 0.120396 0.3048)
			(end 0.120396 0.2794)
			(stroke
				(width 0.1)
				(type default)
			)
			(layer "F.Fab")
		)
		(fp_line
			(start -0.12065 0.3048)
			(end -0.67945 0.3048)
			(stroke
				(width 0.1)
				(type default)
			)
			(layer "F.Fab")
		)
		(fp_line
			(start -0.67945 0.3048)
			(end -0.67945 -0.305054)
			(stroke
				(width 0.1)
				(type default)
			)
			(layer "F.Fab")
		)
		(pad "1" smd circle
			(at -0.40005 0 90)
			(size 0 0)
			(layers "F.Cu" "F.Mask" "F.Paste")
			(net "P12V_SSD6")
		)
		(pad "2" smd circle
			(at 0.40005 0 90)
			(size 0 0)
			(layers "F.Cu" "F.Mask" "F.Paste")
			(net "GND")
		)
	)
	(footprint ""
		(layer "F.Cu")
		(at 445.9478 -236.4994)
		(property "Reference" "R6602"
			(at 0 0 0)
			(layer "F.SilkS")
			(hide yes)
			(effects
				(font
					(size 1.27 1.27)
				)
			)
		)
		(property "Value" ""
			(at 0 0 0)
			(layer "F.Fab")
			(effects
				(font
					(size 1.27 1.27)
				)
			)
		)
		(duplicate_pad_numbers_are_jumpers no)
		(fp_line
			(start -0.7874 -0.4064)
			(end 0.7874 -0.4064)
			(stroke
				(width 0.1524)
				(type default)
			)
			(layer "F.SilkS")
		)
		(fp_line
			(start -0.7874 0.4064)
			(end -0.7874 -0.4064)
			(stroke
				(width 0.1524)
				(type default)
			)
			(layer "F.SilkS")
		)
		(fp_line
			(start 0.7874 -0.4064)
			(end 0.7874 0.4064)
			(stroke
				(width 0.1524)
				(type default)
			)
			(layer "F.SilkS")
		)
		(fp_line
			(start 0.7874 0.4064)
			(end -0.7874 0.4064)
			(stroke
				(width 0.1524)
				(type default)
			)
			(layer "F.SilkS")
		)
		(fp_line
			(start -0.67945 -0.305054)
			(end -0.12065 -0.305054)
			(stroke
				(width 0.1)
				(type default)
			)
			(layer "F.Fab")
		)
		(fp_line
			(start -0.67945 0.3048)
			(end -0.67945 -0.305054)
			(stroke
				(width 0.1)
				(type default)
			)
			(layer "F.Fab")
		)
		(fp_line
			(start -0.12065 -0.305054)
			(end -0.12065 -0.2794)
			(stroke
				(width 0.1)
				(type default)
			)
			(layer "F.Fab")
		)
		(fp_line
			(start -0.12065 -0.2794)
			(end 0.12065 -0.2794)
			(stroke
				(width 0.1)
				(type default)
			)
			(layer "F.Fab")
		)
		(fp_line
			(start -0.12065 0.2794)
			(end -0.12065 0.3048)
			(stroke
				(width 0.1)
				(type default)
			)
			(layer "F.Fab")
		)
		(fp_line
			(start -0.12065 0.3048)
			(end -0.67945 0.3048)
			(stroke
				(width 0.1)
				(type default)
			)
			(layer "F.Fab")
		)
		(fp_line
			(start 0.120396 0.2794)
			(end -0.12065 0.2794)
			(stroke
				(width 0.1)
				(type default)
			)
			(layer "F.Fab")
		)
		(fp_line
			(start 0.120396 0.3048)
			(end 0.120396 0.2794)
			(stroke
				(width 0.1)
				(type default)
			)
			(layer "F.Fab")
		)
		(fp_line
			(start 0.12065 -0.3048)
			(end 0.67945 -0.3048)
			(stroke
				(width 0.1)
				(type default)
			)
			(layer "F.Fab")
		)
		(fp_line
			(start 0.12065 -0.2794)
			(end 0.12065 -0.3048)
			(stroke
				(width 0.1)
				(type default)
			)
			(layer "F.Fab")
		)
		(fp_line
			(start 0.67945 -0.3048)
			(end 0.67945 0.3048)
			(stroke
				(width 0.1)
				(type default)
			)
			(layer "F.Fab")
		)
		(fp_line
			(start 0.67945 0.3048)
			(end 0.120396 0.3048)
			(stroke
				(width 0.1)
				(type default)
			)
			(layer "F.Fab")
		)
		(pad "1" smd circle
			(at -0.40005 0)
			(size 0 0)
			(layers "F.Cu" "F.Mask" "F.Paste")
			(net "P3V3_AUX")
		)
		(pad "2" smd circle
			(at 0.40005 0)
			(size 0 0)
			(layers "F.Cu" "F.Mask" "F.Paste")
			(net "RST_CP2108_SDB_R_N")
		)
	)
)
